( ConstraintFile "p3v3_stby"
	( constraintHeader
		( objectKey
			( logical )
		)
		( version
			( 16.5 )
		)
		( revisionNumber
			( logicalViewRevNum 2 )
			( physicalViewRevNum 0 )
			( otherViewRevNum 0 )
		)
		( contents
			( dictionaryExtensions )
			( worksheetCustomizations )
			( electricalConstraints )
			( netClasses )
			( properties )
		)
		( precision
			( units mil )
			( numberOfDecimalPlaces 2 )
		)
	)
	( DictionaryExtensions
		( Attribute
			( Name "MATERIAL" )
			( Description " " )
			( Value
				( DataType ( dString ) )
				( Status  sProperty  sPackage )
			)
			( Objects
				( ValidObjects  oGate  oGateDefn  oBlock  oPart  oDesign  oSystem  oPartDefn )
				( NoInherit
					( oGate oPin )
				)
			)
			( Analysis
			)
		)
		( Attribute
			( Name "TOLERANCE" )
			( Description " " )
			( Value
				( DataType ( dString ) )
				( Status  sProperty  sPackage )
			)
			( Objects
				( ValidObjects  oGate  oGateDefn  oBlock  oPart  oDesign  oSystem  oPartDefn )
				( NoInherit
					( oGate oPin )
				)
			)
			( Analysis
			)
		)
		( Attribute
			( Name "WATTAGE" )
			( Description " " )
			( Value
				( DataType ( dString ) )
				( Status  sProperty  sPackage )
			)
			( Objects
				( ValidObjects  oGate  oGateDefn  oBlock  oPart  oDesign  oSystem  oPartDefn )
				( NoInherit
					( oGate oPin )
				)
			)
			( Analysis
			)
		)
		( Attribute
			( Name "CDS_LMAN_SYM_OUTLINE" )
			( Description " " )
			( Value
				( DataType ( dString ) )
				( Status  sProperty  sPackage )
			)
			( Objects
				( ValidObjects  oGate  oGateDefn  oBlock  oPart  oDesign  oSystem  oPartDefn )
				( NoInherit
					( oGate oPin )
				)
			)
			( Analysis
			)
		)
		( Attribute
			( Name "SEC_TYPE" )
			( Description " " )
			( Value
				( DataType ( dString ) )
				( Status  sProperty  sPackage )
			)
			( Objects
				( ValidObjects  oGate  oGateDefn  oBlock  oPart  oDesign  oSystem  oPartDefn )
				( NoInherit
					( oGate oPin )
				)
			)
			( Analysis
			)
		)
		( Attribute
			( Name "$sec" )
			( Description "" )
			( Value
				( DataType ( dString ) )
				( Status  sProperty )
			)
			( Objects
				( ValidObjects  oAll )
			)
			( Analysis
			)
		)
		( Attribute
			( Name "$location" )
			( Description "" )
			( Value
				( DataType ( dString ) )
				( Status  sProperty )
			)
			( Objects
				( ValidObjects  oAll )
			)
			( Analysis
			)
		)
		( Attribute
			( Name "WACKO" )
			( Description " " )
			( Value
				( DataType ( dString ) )
				( Status  sProperty  sPackage )
			)
			( Objects
				( ValidObjects  oGate  oGateDefn  oBlock  oPart  oDesign  oSystem  oPartDefn )
				( NoInherit
					( oGate oPin )
				)
			)
			( Analysis
			)
		)
		( Attribute
			( Name "BODY_TYPE" )
			( Description " " )
			( Value
				( DataType ( dString ) )
				( Status  sProperty  sPackage )
			)
			( Objects
				( ValidObjects  oGate  oBlock  oPart  oDesign  oSystem  oGateDefn  oPartDefn )
			)
			( Analysis
			)
		)
	)
	( designConstraints
		( ruleChanges
			( allRules )
			( design "p3v3_stby"
			)
			( signal "@mstr_symbols.p3v3_stby(sch_1):g"
				( objectFlag fObjectAlias )
				( objectStatus "g" )
			)
			( signal "@mstr_symbols.p3v3_stby(sch_1):page1_g"
				( objectFlag fObjectAlias )
				( objectStatus "page1_g" )
			)
			( signal "@mstr_symbols.p3v3_stby(sch_1):p3v3_stby"
				( alias ( signalRef "@mstr_symbols.p3v3_stby(sch_1):page1_p3v3_stby") )
				( alias ( signalRef "@mstr_symbols.p3v3_stby(sch_1):page1_g") )
				( alias ( signalRef "@mstr_symbols.p3v3_stby(sch_1):g") )
				( objectStatus "p3v3_stby" )
			)
			( signal "@mstr_symbols.p3v3_stby(sch_1):page1_p3v3_stby"
				( objectFlag fObjectAlias )
				( objectStatus "page1_p3v3_stby" )
			)
		)
	)
)
